# TIMECARD (Time Appliance Project (Time Card)) — schematic netlist excerpt (pin names and nets, part order shuffled) for the footprints in the layout excerpt that follows; sources: Cadence DE-HDL packaged netlist, KiCad conversion of R4006-B0001-02_R01.brd

C95  CAPACITOR  0.1UF 25V 10%  pkg SMC_0402R_H022  page 24 : \1\ = XP3R3V_FT4232 ; \2\ = SG
C222  CAPACITOR  0.1UF 10V 10%  pkg SMC_0402R_H022  page 14 : \1\ = XP1R0V_FPGA_VCCINT ; \2\ = SG

(kicad_pcb
	(version 20260206)
	(generator "pcbnew")
	(generator_version "10.0")
	(general
		(thickness 1.6)
		(legacy_teardrops no)
	)
	(paper "A4")
	(title_block
		(title "timecard-production-celestica-r4006 — R4006-B0001-02_R01.brd")
		(comment 1 "Time Appliance Project (Time Card) / footprints 728-729 of 1113")
	)
	(layers
		(0 "F.Cu" signal "TOP")
		(4 "In1.Cu" signal "L02_GND1")
		(6 "In2.Cu" signal "L03_SIG1")
		(8 "In3.Cu" signal "L04_GND2")
		(10 "In4.Cu" signal "L05_VCC1")
		(12 "In5.Cu" signal "L06_VCC2")
		(14 "In6.Cu" signal "L07_GND3")
		(16 "In7.Cu" signal "L08_SIG2")
		(18 "In8.Cu" signal "L09_GND4")
		(2 "B.Cu" signal "BOTTOM")
		(9 "F.Adhes" user "F.Adhesive")
		(11 "B.Adhes" user "B.Adhesive")
		(13 "F.Paste" user "Package Geometry/Pastemask Top")
		(15 "B.Paste" user "Package Geometry/Pastemask Bottom")
		(5 "F.SilkS" user "Ref Des/Silkscreen Top")
		(7 "B.SilkS" user "Ref Des/Silkscreen Bottom")
		(1 "F.Mask" user "Board Geometry/Soldermask Top")
		(3 "B.Mask" user "Board Geometry/Soldermask Bottom")
		(17 "Dwgs.User" user "User.Drawings")
		(19 "Cmts.User" user "User.Comments")
		(21 "Eco1.User" user "User.Eco1")
		(23 "Eco2.User" user "User.Eco2")
		(25 "Edge.Cuts" user "Board Geometry/Outline")
		(27 "Margin" user)
		(31 "F.CrtYd" user "Package Geometry/Place Bound Top")
		(29 "B.CrtYd" user "Package Geometry/Place Bound Bottom")
		(35 "F.Fab" user "Ref Des/Assembly Top")
		(33 "B.Fab" user "Ref Des/Assembly Bottom")
	)
	(footprint ""
		(layer "B.Cu")
		(at 29.845 -88.265 180)
		(property "Reference" "C95"
			(at -0.381 -1.30937 0)
			(unlocked yes)
			(layer "B.SilkS")
			(effects
				(font
					(size 0.7874 0.5842)
					(thickness 0.1524)
				)
				(justify mirror)
			)
		)
		(property "Value" "VAL*"
			(at -0.0762 2.067306 180)
			(unlocked yes)
			(layer "B.Fab")
			(hide yes)
			(effects
				(font
					(size 0.7874 0.5842)
					(thickness 0.1524)
				)
				(justify mirror)
			)
		)
		(property "Tolerance" "TOL*"
			(at -0.0762 3.032506 180)
			(unlocked yes)
			(layer "Cmts.User")
			(hide yes)
			(effects
				(font
					(size 0.7874 0.5842)
					(thickness 0.1524)
				)
				(justify mirror)
			)
		)
		(property "User Part Number" "PARTNUM*"
			(at -0.1016 4.023106 180)
			(unlocked yes)
			(layer "Cmts.User")
			(hide yes)
			(effects
				(font
					(size 0.7874 0.5842)
					(thickness 0.1524)
				)
				(justify mirror)
			)
		)
		(property "Device Type" "CAPACITOR-G105-0B104-CK,0.1UF,A"
			(at -0.0508 1.127506 180)
			(unlocked yes)
			(layer "B.Fab")
			(hide yes)
			(effects
				(font
					(size 0.7874 0.5842)
					(thickness 0.1524)
				)
				(justify mirror)
			)
		)
		(duplicate_pad_numbers_are_jumpers no)
		(fp_line
			(start 1.143 0.5588)
			(end -1.143 0.5588)
			(stroke
				(width 0.1)
				(type default)
			)
			(layer "B.SilkS")
		)
		(fp_line
			(start 1.143 -0.5588)
			(end 1.143 0.5588)
			(stroke
				(width 0.1)
				(type default)
			)
			(layer "B.SilkS")
		)
		(fp_line
			(start -1.143 0.5588)
			(end -1.143 -0.5588)
			(stroke
				(width 0.1)
				(type default)
			)
			(layer "B.SilkS")
		)
		(fp_line
			(start -1.143 -0.5588)
			(end 1.143 -0.5588)
			(stroke
				(width 0.1)
				(type default)
			)
			(layer "B.SilkS")
		)
		(fp_rect
			(start 1.143 -0.5588)
			(end -1.143 0.5588)
			(stroke
				(width 0)
				(type default)
			)
			(fill no)
			(layer "B.CrtYd")
		)
		(fp_line
			(start 0.508 0.3048)
			(end -0.508 0.3048)
			(stroke
				(width 0.1)
				(type default)
			)
			(layer "B.Fab")
		)
		(fp_line
			(start 0.508 -0.3048)
			(end 0.508 0.3048)
			(stroke
				(width 0.1)
				(type default)
			)
			(layer "B.Fab")
		)
		(fp_line
			(start -0.508 0.3048)
			(end -0.508 -0.3048)
			(stroke
				(width 0.1)
				(type default)
			)
			(layer "B.Fab")
		)
		(fp_line
			(start -0.508 -0.3048)
			(end 0.508 -0.3048)
			(stroke
				(width 0.1)
				(type default)
			)
			(layer "B.Fab")
		)
		(pad "1" smd rect
			(at 0.5334 0)
			(size 0.7112 0.6096)
			(layers "B.Cu" "B.Mask" "B.Paste")
			(net "XP3R3V_FT4232")
		)
		(pad "2" smd rect
			(at -0.5334 0)
			(size 0.7112 0.6096)
			(layers "B.Cu" "B.Mask" "B.Paste")
			(net "SG")
		)
		(zone
			(layer "B.Cu")
			(hatch none 0.5)
			(connect_pads
				(clearance 0)
			)
			(min_thickness 0.25)
			(keepout
				(tracks allowed)
				(vias not_allowed)
				(pads allowed)
				(copperpour not_allowed)
				(footprints allowed)
			)
			(placement
				(enabled no)
				(sheetname "")
			)
			(fill
				(thermal_gap 0.5)
				(thermal_bridge_width 0.5)
				(island_removal_mode 0)
			)
			(polygon
				(pts
					(xy 29.7688 -87.9602) (xy 29.9212 -87.9602) (xy 29.9212 -88.5698) (xy 29.7688 -88.5698)
				)
			)
		)
	)
	(footprint ""
		(layer "B.Cu")
		(at 104.847136 -42.323004 90)
		(property "Reference" "C222"
			(at -1.141984 -41.510966 270)
			(unlocked yes)
			(layer "B.SilkS")
			(effects
				(font
					(size 0.635 0.4064)
					(thickness 0.1524)
				)
				(justify mirror)
			)
		)
		(property "Value" "VAL*"
			(at 0 3.718306 90)
			(unlocked yes)
			(layer "B.Fab")
			(hide yes)
			(effects
				(font
					(size 0.7874 0.5842)
					(thickness 0.127)
				)
				(justify mirror)
			)
		)
		(property "Tolerance" "TOL*"
			(at 0 4.861306 90)
			(unlocked yes)
			(layer "Cmts.User")
			(hide yes)
			(effects
				(font
					(size 0.7874 0.5842)
					(thickness 0.127)
				)
				(justify mirror)
			)
		)
		(property "User Part Number" "PARTNUM*"
			(at 0 2.575306 90)
			(unlocked yes)
			(layer "Cmts.User")
			(hide yes)
			(effects
				(font
					(size 0.7874 0.5842)
					(thickness 0.127)
				)
				(justify mirror)
			)
		)
		(property "Device Type" "CAPACITOR-G105-0B104-CK,0.1UF,A"
			(at 0 1.432306 90)
			(unlocked yes)
			(layer "B.Fab")
			(hide yes)
			(effects
				(font
					(size 0.7874 0.5842)
					(thickness 0.127)
				)
				(justify mirror)
			)
		)
		(duplicate_pad_numbers_are_jumpers no)
		(fp_line
			(start 0.970026 -0.4699)
			(end -0.970026 -0.4699)
			(stroke
				(width 0.1)
				(type default)
			)
			(layer "B.SilkS")
		)
		(fp_line
			(start -0.970026 -0.4699)
			(end -0.970026 0.4699)
			(stroke
				(width 0.1)
				(type default)
			)
			(layer "B.SilkS")
		)
		(fp_line
			(start 0.970026 0.4699)
			(end 0.970026 -0.4699)
			(stroke
				(width 0.1)
				(type default)
			)
			(layer "B.SilkS")
		)
		(fp_line
			(start -0.970026 0.4699)
			(end 0.970026 0.4699)
			(stroke
				(width 0.1)
				(type default)
			)
			(layer "B.SilkS")
		)
		(fp_poly
			(pts
				(xy 0.970026 0.4699) (xy -0.970026 0.4699) (xy -0.970026 -0.4699) (xy 0.970026 -0.4699)
			)
			(stroke
				(width 0)
				(type default)
			)
			(fill no)
			(layer "B.CrtYd")
		)
		(fp_line
			(start 0.508 -0.3048)
			(end -0.508 -0.3048)
			(stroke
				(width 0.1)
				(type default)
			)
			(layer "B.Fab")
		)
		(fp_line
			(start -0.508 -0.3048)
			(end -0.508 0.3048)
			(stroke
				(width 0.1)
				(type default)
			)
			(layer "B.Fab")
		)
		(fp_line
			(start 0.508 0.3048)
			(end 0.508 -0.3048)
			(stroke
				(width 0.1)
				(type default)
			)
			(layer "B.Fab")
		)
		(fp_line
			(start -0.508 0.3048)
			(end 0.508 0.3048)
			(stroke
				(width 0.1)
				(type default)
			)
			(layer "B.Fab")
		)
		(pad "1" smd circle
			(at 0.500126 0 270)
			(size 0.635 0.635)
			(layers "B.Cu" "B.Mask" "B.Paste")
			(net "XP1R0V_FPGA_VCCINT")
		)
		(pad "2" smd circle
			(at -0.500126 0 270)
			(size 0.635 0.635)
			(layers "B.Cu" "B.Mask" "B.Paste")
			(net "SG")
		)
	)
)
